# T6G (Grand Teton) — schematic netlist excerpt (pin names and nets, part order shuffled) for the footprints in the layout excerpt that follows; sources: Cadence DE-HDL packaged netlist, KiCad conversion of 04192023_DAF0TMB3IC0_F0TG_MB_C_brd_V02_OCP.brd

C6662  Q_CAP_DIFFBUS  DIFF BUS_0.22UF 6.3V 20% X6S  pkg C0201  page 330 : \1\ = P5E_CPU1_P1_TX_BUF_C_DN<0> ; \2\ = P5E_CPU1_P1_TX_BUF_DN<0>
C2409  Q_CAP  22UF 4V 20% X6S  pkg C0402  page 74 : A = PVDDCR_SOC_P1 ; B = GND
R1686  Q_RES  10 1% CHIP  pkg 0402LF  page 97 : A = I3C_SPD_DDRGL_CPU0_SDA ; B = I3C_SPD_DDRL_CPU0_SDA

(kicad_pcb
	(version 20260206)
	(generator "pcbnew")
	(generator_version "10.0")
	(general
		(thickness 1.6)
		(legacy_teardrops no)
	)
	(paper "A4")
	(title_block
		(title "04192023_DAF0TMB3IC0_F0TG_MB_C_brd_V02_OCP.brd")
		(comment 1 "Grand Teton / footprints 5006-5008 of 8354")
	)
	(layers
		(0 "F.Cu" signal "TOP")
		(4 "In1.Cu" signal "GND")
		(6 "In2.Cu" signal "IN1")
		(8 "In3.Cu" signal "GND1")
		(10 "In4.Cu" signal "IN2")
		(12 "In5.Cu" signal "GND2")
		(14 "In6.Cu" signal "IN3")
		(16 "In7.Cu" signal "GND3")
		(18 "In8.Cu" signal "VCC")
		(20 "In9.Cu" signal "VCC1")
		(22 "In10.Cu" signal "GND4")
		(24 "In11.Cu" signal "IN4")
		(26 "In12.Cu" signal "GND5")
		(28 "In13.Cu" signal "IN5")
		(30 "In14.Cu" signal "GND6")
		(32 "In15.Cu" signal "IN6")
		(34 "In16.Cu" signal "GND7")
		(2 "B.Cu" signal "BOTTOM")
		(9 "F.Adhes" user "F.Adhesive")
		(11 "B.Adhes" user "B.Adhesive")
		(13 "F.Paste" user "Package Geometry/Pastemask Top")
		(15 "B.Paste" user "Package Geometry/Pastemask Bottom")
		(5 "F.SilkS" user "Ref Des/Silkscreen Top")
		(7 "B.SilkS" user "Ref Des/Silkscreen Bottom")
		(1 "F.Mask" user "Board Geometry/Soldermask Top")
		(3 "B.Mask" user "Board Geometry/Soldermask Bottom")
		(17 "Dwgs.User" user "User.Drawings")
		(19 "Cmts.User" user "User.Comments")
		(21 "Eco1.User" user "User.Eco1")
		(23 "Eco2.User" user "User.Eco2")
		(25 "Edge.Cuts" user "Board Geometry/Outline")
		(27 "Margin" user)
		(31 "F.CrtYd" user "Package Geometry/Place Bound Top")
		(29 "B.CrtYd" user "Package Geometry/Place Bound Bottom")
		(35 "F.Fab" user "Ref Des/Assembly Top")
		(33 "B.Fab" user "Ref Des/Assembly Bottom")
	)
	(footprint ""
		(layer "B.Cu")
		(at 453.432418 -195.92671 180)
		(property "Reference" "R1686"
			(at 0 0 0)
			(layer "B.SilkS")
			(hide yes)
			(effects
				(font
					(size 1.27 1.27)
				)
				(justify mirror)
			)
		)
		(property "Value" ""
			(at 0 0 0)
			(layer "B.Fab")
			(effects
				(font
					(size 1.27 1.27)
				)
				(justify mirror)
			)
		)
		(duplicate_pad_numbers_are_jumpers no)
		(fp_line
			(start 0.7874 0.4064)
			(end 0.7874 -0.4064)
			(stroke
				(width 0.1524)
				(type default)
			)
			(layer "B.SilkS")
		)
		(fp_line
			(start 0.7874 -0.4064)
			(end -0.7874 -0.4064)
			(stroke
				(width 0.1524)
				(type default)
			)
			(layer "B.SilkS")
		)
		(fp_line
			(start -0.7874 0.4064)
			(end 0.7874 0.4064)
			(stroke
				(width 0.1524)
				(type default)
			)
			(layer "B.SilkS")
		)
		(fp_line
			(start -0.7874 -0.4064)
			(end -0.7874 0.4064)
			(stroke
				(width 0.1524)
				(type default)
			)
			(layer "B.SilkS")
		)
		(fp_line
			(start 0.67945 0.3048)
			(end 0.67945 -0.305054)
			(stroke
				(width 0.1)
				(type default)
			)
			(layer "B.Fab")
		)
		(fp_line
			(start 0.67945 -0.305054)
			(end 0.12065 -0.305054)
			(stroke
				(width 0.1)
				(type default)
			)
			(layer "B.Fab")
		)
		(fp_line
			(start 0.12065 0.3048)
			(end 0.67945 0.3048)
			(stroke
				(width 0.1)
				(type default)
			)
			(layer "B.Fab")
		)
		(fp_line
			(start 0.12065 0.2794)
			(end 0.12065 0.3048)
			(stroke
				(width 0.1)
				(type default)
			)
			(layer "B.Fab")
		)
		(fp_line
			(start 0.12065 -0.2794)
			(end -0.12065 -0.2794)
			(stroke
				(width 0.1)
				(type default)
			)
			(layer "B.Fab")
		)
		(fp_line
			(start 0.12065 -0.305054)
			(end 0.12065 -0.2794)
			(stroke
				(width 0.1)
				(type default)
			)
			(layer "B.Fab")
		)
		(fp_line
			(start -0.120396 0.3048)
			(end -0.120396 0.2794)
			(stroke
				(width 0.1)
				(type default)
			)
			(layer "B.Fab")
		)
		(fp_line
			(start -0.120396 0.2794)
			(end 0.12065 0.2794)
			(stroke
				(width 0.1)
				(type default)
			)
			(layer "B.Fab")
		)
		(fp_line
			(start -0.12065 -0.2794)
			(end -0.12065 -0.3048)
			(stroke
				(width 0.1)
				(type default)
			)
			(layer "B.Fab")
		)
		(fp_line
			(start -0.12065 -0.3048)
			(end -0.67945 -0.3048)
			(stroke
				(width 0.1)
				(type default)
			)
			(layer "B.Fab")
		)
		(fp_line
			(start -0.67945 0.3048)
			(end -0.120396 0.3048)
			(stroke
				(width 0.1)
				(type default)
			)
			(layer "B.Fab")
		)
		(fp_line
			(start -0.67945 -0.3048)
			(end -0.67945 0.3048)
			(stroke
				(width 0.1)
				(type default)
			)
			(layer "B.Fab")
		)
		(pad "1" smd circle
			(at 0.40005 0)
			(size 0 0)
			(layers "B.Cu" "B.Mask" "B.Paste")
			(net "I3C_SPD_DDRGL_CPU0_SDA")
		)
		(pad "2" smd circle
			(at -0.40005 0)
			(size 0 0)
			(layers "B.Cu" "B.Mask" "B.Paste")
			(net "I3C_SPD_DDRL_CPU0_SDA")
		)
	)
	(footprint ""
		(layer "B.Cu")
		(at 102.214934 -252.234192 60)
		(property "Reference" "C2409"
			(at 0 0 60)
			(layer "B.SilkS")
			(hide yes)
			(effects
				(font
					(size 1.27 1.27)
				)
				(justify mirror)
			)
		)
		(property "Value" ""
			(at 0 0 60)
			(layer "B.Fab")
			(effects
				(font
					(size 1.27 1.27)
				)
				(justify mirror)
			)
		)
		(duplicate_pad_numbers_are_jumpers no)
		(fp_line
			(start -0.787516 -0.406438)
			(end -0.787425 0.40652)
			(stroke
				(width 0.1524)
				(type default)
			)
			(layer "B.SilkS")
		)
		(fp_line
			(start -0.787425 0.40652)
			(end 0.787516 0.406438)
			(stroke
				(width 0.1524)
				(type default)
			)
			(layer "B.SilkS")
		)
		(fp_line
			(start 0.787425 -0.40652)
			(end -0.787516 -0.406438)
			(stroke
				(width 0.1524)
				(type default)
			)
			(layer "B.SilkS")
		)
		(fp_line
			(start 0.787516 0.406438)
			(end 0.787425 -0.40652)
			(stroke
				(width 0.1524)
				(type default)
			)
			(layer "B.SilkS")
		)
		(fp_line
			(start -0.679568 -0.304811)
			(end -0.6795 0.304908)
			(stroke
				(width 0.1)
				(type default)
			)
			(layer "B.Fab")
		)
		(fp_line
			(start -0.120605 -0.304905)
			(end -0.679568 -0.304811)
			(stroke
				(width 0.1)
				(type default)
			)
			(layer "B.Fab")
		)
		(fp_line
			(start -0.120554 -0.279418)
			(end -0.120605 -0.304905)
			(stroke
				(width 0.1)
				(type default)
			)
			(layer "B.Fab")
		)
		(fp_line
			(start 0.120629 -0.30516)
			(end 0.120587 -0.279326)
			(stroke
				(width 0.1)
				(type default)
			)
			(layer "B.Fab")
		)
		(fp_line
			(start 0.120587 -0.279326)
			(end -0.120554 -0.279418)
			(stroke
				(width 0.1)
				(type default)
			)
			(layer "B.Fab")
		)
		(fp_line
			(start -0.6795 0.304908)
			(end -0.120316 0.304686)
			(stroke
				(width 0.1)
				(type default)
			)
			(layer "B.Fab")
		)
		(fp_line
			(start 0.679373 -0.305128)
			(end 0.120629 -0.30516)
			(stroke
				(width 0.1)
				(type default)
			)
			(layer "B.Fab")
		)
		(fp_line
			(start -0.12024 0.279419)
			(end 0.120554 0.279418)
			(stroke
				(width 0.1)
				(type default)
			)
			(layer "B.Fab")
		)
		(fp_line
			(start -0.120316 0.304686)
			(end -0.12024 0.279419)
			(stroke
				(width 0.1)
				(type default)
			)
			(layer "B.Fab")
		)
		(fp_line
			(start 0.120554 0.279418)
			(end 0.120605 0.304905)
			(stroke
				(width 0.1)
				(type default)
			)
			(layer "B.Fab")
		)
		(fp_line
			(start 0.120605 0.304905)
			(end 0.679568 0.304811)
			(stroke
				(width 0.1)
				(type default)
			)
			(layer "B.Fab")
		)
		(fp_line
			(start 0.679568 0.304811)
			(end 0.679373 -0.305128)
			(stroke
				(width 0.1)
				(type default)
			)
			(layer "B.Fab")
		)
		(pad "1" smd circle
			(at 0.40005 0 240)
			(size 0 0)
			(layers "B.Cu" "B.Mask" "B.Paste")
			(net "PVDDCR_SOC_P1")
		)
		(pad "2" smd circle
			(at -0.40005 0 240)
			(size 0 0)
			(layers "B.Cu" "B.Mask" "B.Paste")
			(net "GND")
		)
	)
	(footprint ""
		(layer "B.Cu")
		(at 49.300384 -408.517344 90)
		(property "Reference" "C6662"
			(at 0 0 90)
			(layer "B.SilkS")
			(hide yes)
			(effects
				(font
					(size 1.27 1.27)
				)
				(justify mirror)
			)
		)
		(property "Value" ""
			(at 0 0 90)
			(layer "B.Fab")
			(effects
				(font
					(size 1.27 1.27)
				)
				(justify mirror)
			)
		)
		(duplicate_pad_numbers_are_jumpers no)
		(fp_line
			(start 0.299974 -0.150114)
			(end -0.299974 -0.150114)
			(stroke
				(width 0.1)
				(type default)
			)
			(layer "B.Fab")
		)
		(fp_line
			(start -0.299974 -0.150114)
			(end -0.299974 0.150114)
			(stroke
				(width 0.1)
				(type default)
			)
			(layer "B.Fab")
		)
		(fp_line
			(start 0.299974 0.150114)
			(end 0.299974 -0.150114)
			(stroke
				(width 0.1)
				(type default)
			)
			(layer "B.Fab")
		)
		(fp_line
			(start -0.299974 0.150114)
			(end 0.299974 0.150114)
			(stroke
				(width 0.1)
				(type default)
			)
			(layer "B.Fab")
		)
		(pad "1" smd rect
			(at 0.2667 0 270)
			(size 0.3048 0.381)
			(layers "B.Cu" "B.Mask" "B.Paste")
			(net "P5E_CPU1_P1_TX_BUF_C_DN<0>")
		)
		(pad "2" smd rect
			(at -0.2667 0 270)
			(size 0.3048 0.381)
			(layers "B.Cu" "B.Mask" "B.Paste")
			(net "P5E_CPU1_P1_TX_BUF_DN<0>")
		)
	)
)
